# BASEBOARD_FAB2 (Tioga Pass) — schematic netlist excerpt (pin names and nets, part order shuffled) for the footprints in the layout excerpt that follows; sources: Cadence DE-HDL packaged netlist, KiCad conversion of Wiwynn_Tioga_Pass_MB.brd

R3W1  RES  1.00K 1% CHIP  pkg 0402  page 249 : A = BMC_SELF_HW_D_RST ; B = GND
C25W49  CAP_A  0.1UF 16V 10% X7R  pkg 0402V  page 149 : A = P3V3_STBY ; B = GND
F1L1  FUSE  IC  pkg SMT  page 155 : A(0) = P5V_STBY_DBG ; B(0) = P5V_STBY_DGB_FS

(kicad_pcb
	(version 20260206)
	(generator "pcbnew")
	(generator_version "10.0")
	(general
		(thickness 1.6)
		(legacy_teardrops no)
	)
	(paper "A4")
	(title_block
		(title "Wiwynn_Tioga_Pass_MB.brd")
		(comment 1 "Tioga Pass / footprints 3938-3940 of 4770")
	)
	(layers
		(0 "F.Cu" signal "TOP")
		(4 "In1.Cu" signal "L2GND")
		(6 "In2.Cu" signal "L3")
		(8 "In3.Cu" signal "L4GND")
		(10 "In4.Cu" signal "L5")
		(12 "In5.Cu" signal "L6GND")
		(14 "In6.Cu" signal "L7VCC")
		(16 "In7.Cu" signal "L8VCC")
		(18 "In8.Cu" signal "L9GND")
		(20 "In9.Cu" signal "L10")
		(22 "In10.Cu" signal "L11GND")
		(24 "In11.Cu" signal "L12")
		(26 "In12.Cu" signal "L13GND")
		(2 "B.Cu" signal "BOTTOM")
		(9 "F.Adhes" user "F.Adhesive")
		(11 "B.Adhes" user "B.Adhesive")
		(13 "F.Paste" user "Package Geometry/Pastemask Top")
		(15 "B.Paste" user "Package Geometry/Pastemask Bottom")
		(5 "F.SilkS" user "Ref Des/Silkscreen Top")
		(7 "B.SilkS" user "Ref Des/Silkscreen Bottom")
		(1 "F.Mask" user "Board Geometry/Soldermask Top")
		(3 "B.Mask" user "Board Geometry/Soldermask Bottom")
		(17 "Dwgs.User" user "User.Drawings")
		(19 "Cmts.User" user "User.Comments")
		(21 "Eco1.User" user "User.Eco1")
		(23 "Eco2.User" user "User.Eco2")
		(25 "Edge.Cuts" user "Board Geometry/Outline")
		(27 "Margin" user)
		(31 "F.CrtYd" user "Package Geometry/Place Bound Top")
		(29 "B.CrtYd" user "Package Geometry/Place Bound Bottom")
		(35 "F.Fab" user "Ref Des/Assembly Top")
		(33 "B.Fab" user "Ref Des/Assembly Bottom")
	)
	(footprint ""
		(layer "B.Cu")
		(at 411.505146 -34.934652 -90)
		(property "Reference" "C25W49"
			(at 0.8382 -0.67818 270)
			(unlocked yes)
			(layer "B.SilkS")
			(effects
				(font
					(size 0.4064 0.254)
					(thickness 0.1524)
				)
				(justify left mirror)
			)
		)
		(property "Value" ""
			(at 0 0 90)
			(layer "B.Fab")
			(effects
				(font
					(size 1.27 1.27)
				)
				(justify mirror)
			)
		)
		(duplicate_pad_numbers_are_jumpers no)
		(fp_poly
			(pts
				(xy -0.3048 -0.1016) (xy -0.3048 0.9906) (xy 0.3048 0.9906) (xy 0.3048 -0.1016)
			)
			(stroke
				(width 0)
				(type default)
			)
			(fill no)
			(layer "B.CrtYd")
		)
		(fp_line
			(start -0.3048 0.9906)
			(end -0.3048 -0.1016)
			(stroke
				(width 0.1)
				(type default)
			)
			(layer "B.Fab")
		)
		(fp_line
			(start 0.3048 0.9906)
			(end -0.3048 0.9906)
			(stroke
				(width 0.1)
				(type default)
			)
			(layer "B.Fab")
		)
		(fp_line
			(start -0.3048 -0.1016)
			(end 0.3048 -0.1016)
			(stroke
				(width 0.1)
				(type default)
			)
			(layer "B.Fab")
		)
		(fp_line
			(start 0.3048 -0.1016)
			(end 0.3048 0.9906)
			(stroke
				(width 0.1)
				(type default)
			)
			(layer "B.Fab")
		)
		(pad "1" smd rect
			(at 0 0 90)
			(size 0.508 0.508)
			(layers "B.Cu" "B.Mask" "B.Paste")
			(net "P3V3_STBY")
		)
		(pad "2" smd rect
			(at 0 0.889 90)
			(size 0.508 0.508)
			(layers "B.Cu" "B.Mask" "B.Paste")
			(net "GND")
		)
		(zone
			(layer "B.Cu")
			(hatch none 0.5)
			(connect_pads
				(clearance 0)
			)
			(min_thickness 0.25)
			(keepout
				(tracks not_allowed)
				(vias allowed)
				(pads allowed)
				(copperpour not_allowed)
				(footprints allowed)
			)
			(placement
				(enabled no)
				(sheetname "")
			)
			(fill
				(thermal_gap 0.5)
				(thermal_bridge_width 0.5)
				(island_removal_mode 0)
			)
			(polygon
				(pts
					(xy 410.870146 -34.680652) (xy 410.870146 -35.188652) (xy 411.251146 -35.188652) (xy 411.251146 -34.680652)
				)
			)
		)
		(zone
			(layer "B.Cu")
			(hatch none 0.5)
			(connect_pads
				(clearance 0)
			)
			(min_thickness 0.25)
			(keepout
				(tracks allowed)
				(vias not_allowed)
				(pads allowed)
				(copperpour not_allowed)
				(footprints allowed)
			)
			(placement
				(enabled no)
				(sheetname "")
			)
			(fill
				(thermal_gap 0.5)
				(thermal_bridge_width 0.5)
				(island_removal_mode 0)
			)
			(polygon
				(pts
					(xy 411.251146 -34.680652) (xy 411.251146 -35.188652) (xy 410.870146 -35.188652) (xy 410.870146 -34.680652)
				)
			)
		)
	)
	(footprint ""
		(layer "B.Cu")
		(at 482.592888 -154.917902 -90)
		(property "Reference" "F1L1"
			(at 0 0 90)
			(layer "B.SilkS")
			(hide yes)
			(effects
				(font
					(size 1.27 1.27)
				)
				(justify mirror)
			)
		)
		(property "Value" ""
			(at 0 0 90)
			(layer "B.Fab")
			(effects
				(font
					(size 1.27 1.27)
				)
				(justify mirror)
			)
		)
		(duplicate_pad_numbers_are_jumpers no)
		(fp_poly
			(pts
				(xy 0.2032 -0.4953) (xy 0.2032 0.4953) (xy -1.6002 0.4953) (xy -1.6002 -0.4953)
			)
			(stroke
				(width 0)
				(type default)
			)
			(fill no)
			(layer "B.CrtYd")
		)
		(fp_line
			(start -1.6002 0.4953)
			(end 0.2032 0.4953)
			(stroke
				(width 0.1)
				(type default)
			)
			(layer "B.Fab")
		)
		(fp_line
			(start 0.2032 0.4953)
			(end 0.2032 -0.4953)
			(stroke
				(width 0.1)
				(type default)
			)
			(layer "B.Fab")
		)
		(fp_line
			(start -1.6002 -0.4953)
			(end -1.6002 0.4953)
			(stroke
				(width 0.1)
				(type default)
			)
			(layer "B.Fab")
		)
		(fp_line
			(start 0.2032 -0.4953)
			(end -1.6002 -0.4953)
			(stroke
				(width 0.1)
				(type default)
			)
			(layer "B.Fab")
		)
		(pad "1" smd rect
			(at 0 0 90)
			(size 0.889 0.9906)
			(layers "B.Cu" "B.Mask" "B.Paste")
			(net "P5V_STBY_DBG")
		)
		(pad "2" smd rect
			(at -1.397 0 90)
			(size 0.889 0.9906)
			(layers "B.Cu" "B.Mask" "B.Paste")
			(net "P5V_STBY_DGB_FS")
		)
		(zone
			(layer "B.Cu")
			(hatch none 0.5)
			(connect_pads
				(clearance 0)
			)
			(min_thickness 0.25)
			(keepout
				(tracks not_allowed)
				(vias allowed)
				(pads allowed)
				(copperpour not_allowed)
				(footprints allowed)
			)
			(placement
				(enabled no)
				(sheetname "")
			)
			(fill
				(thermal_gap 0.5)
				(thermal_bridge_width 0.5)
				(island_removal_mode 0)
			)
			(polygon
				(pts
					(xy 483.088188 -155.362402) (xy 482.097588 -155.362402) (xy 482.097588 -155.870402) (xy 483.088188 -155.870402)
				)
			)
		)
	)
	(footprint ""
		(layer "B.Cu")
		(at 451.030594 -17.1831 -90)
		(property "Reference" "R3W1"
			(at 0.8382 -0.67818 270)
			(unlocked yes)
			(layer "B.SilkS")
			(effects
				(font
					(size 0.4064 0.254)
					(thickness 0.1524)
				)
				(justify left mirror)
			)
		)
		(property "Value" ""
			(at 0 0 90)
			(layer "B.Fab")
			(effects
				(font
					(size 1.27 1.27)
				)
				(justify mirror)
			)
		)
		(duplicate_pad_numbers_are_jumpers no)
		(fp_poly
			(pts
				(xy 0.2794 -0.1016) (xy -0.2794 -0.1016) (xy -0.2794 0.9906) (xy 0.2794 0.9906)
			)
			(stroke
				(width 0)
				(type default)
			)
			(fill no)
			(layer "B.CrtYd")
		)
		(fp_line
			(start -0.2794 0.9906)
			(end -0.2794 -0.1016)
			(stroke
				(width 0.1)
				(type default)
			)
			(layer "B.Fab")
		)
		(fp_line
			(start 0.2794 0.9906)
			(end -0.2794 0.9906)
			(stroke
				(width 0.1)
				(type default)
			)
			(layer "B.Fab")
		)
		(fp_line
			(start -0.2794 -0.1016)
			(end 0.2794 -0.1016)
			(stroke
				(width 0.1)
				(type default)
			)
			(layer "B.Fab")
		)
		(fp_line
			(start 0.2794 -0.1016)
			(end 0.2794 0.9906)
			(stroke
				(width 0.1)
				(type default)
			)
			(layer "B.Fab")
		)
		(pad "1" smd rect
			(at 0 0 90)
			(size 0.508 0.508)
			(layers "B.Cu" "B.Mask" "B.Paste")
			(net "BMC_SELF_HW_D_RST")
		)
		(pad "2" smd rect
			(at 0 0.889 90)
			(size 0.508 0.508)
			(layers "B.Cu" "B.Mask" "B.Paste")
			(net "GND")
		)
		(zone
			(layer "B.Cu")
			(hatch none 0.5)
			(connect_pads
				(clearance 0)
			)
			(min_thickness 0.25)
			(keepout
				(tracks not_allowed)
				(vias allowed)
				(pads allowed)
				(copperpour not_allowed)
				(footprints allowed)
			)
			(placement
				(enabled no)
				(sheetname "")
			)
			(fill
				(thermal_gap 0.5)
				(thermal_bridge_width 0.5)
				(island_removal_mode 0)
			)
			(polygon
				(pts
					(xy 450.395594 -16.9291) (xy 450.395594 -17.4371) (xy 450.776594 -17.4371) (xy 450.776594 -16.9291)
				)
			)
		)
		(zone
			(layer "B.Cu")
			(hatch none 0.5)
			(connect_pads
				(clearance 0)
			)
			(min_thickness 0.25)
			(keepout
				(tracks allowed)
				(vias not_allowed)
				(pads allowed)
				(copperpour not_allowed)
				(footprints allowed)
			)
			(placement
				(enabled no)
				(sheetname "")
			)
			(fill
				(thermal_gap 0.5)
				(thermal_bridge_width 0.5)
				(island_removal_mode 0)
			)
			(polygon
				(pts
					(xy 450.776594 -16.9291) (xy 450.776594 -17.4371) (xy 450.395594 -17.4371) (xy 450.395594 -16.9291)
				)
			)
		)
	)
)
